#ISCELL
  mstr_misc dns *
  *
#ISCELL
  pure_quanta quanta_title_block_c *
  *
#ISCELL
  pure_quanta_power bom_note *
  *
#CELL
  pure_quanta q_res *
  page302_i15
#CELL
  pure_quanta q_res *
  page302_i16
#CELL
  pure_quanta q_res *
  page302_i17
#CELL
  pure_quanta q_res *
  page302_i18
#ISCELL
  standard offpage *
  page302_i19
#ISCELL
  standard offpage *
  page302_i20
#ISCELL
  standard offpage *
  page302_i21
#ISCELL
  standard offpage *
  page302_i22
#ISCELL
  standard offpage *
  page302_i23
#ISCELL
  standard offpage *
  page302_i24
#ISCELL
  standard offpage *
  page302_i25
#ISCELL
  standard offpage *
  page302_i26
#CELL
  pure_quanta q_res *
  page302_i27
#CELL
  pure_quanta q_res *
  page302_i28
#CELL
  pure_quanta mosfet_nch_1d3s *
  page302_i29
#ISCELL
  standard offpage *
  page302_i30
#ISCELL
  standard offpage *
  page302_i31
#ISCELL
  standard offpage *
  page302_i32
#ISCELL
  standard offpage *
  page302_i33
#ISCELL
  standard offpage *
  page302_i34
#ISCELL
  standard offpage *
  page302_i35
#ISCELL
  standard offpage *
  page302_i36
#ISCELL
  standard offpage *
  page302_i37
#ISCELL
  standard offpage *
  page302_i38
#ISCELL
  standard offpage *
  page302_i39
#ISCELL
  standard offpage *
  page302_i40
#ISCELL
  standard offpage *
  page302_i41
#ISCELL
  standard offpage *
  page302_i42
#ISCELL
  standard offpage *
  page302_i43
#ISCELL
  standard offpage *
  page302_i44
#CELL
  pure_quanta q_res *
  page302_i45
#CELL
  pure_quanta mosfet_nch_1d3s *
  page302_i46
#CELL
  pure_quanta q_res *
  page302_i47
#ISCELL
  standard offpage *
  page302_i48
#ISCELL
  standard offpage *
  page302_i49
#CELL
  pure_quanta q_res *
  page302_i5
#ISCELL
  standard offpage *
  page302_i50
#ISCELL
  standard offpage *
  page302_i51
#CELL
  pure_quanta q_sp_res4p *
  page302_i52
#CELL
  pure_quanta q_sp_res4p *
  page302_i53
#CELL
  pure_quanta q_sp_res4p *
  page302_i54
#CELL
  pure_quanta q_sp_res4p *
  page302_i55
#ISCELL
  pure_quanta_power universal_power *
  page302_i56
#ISCELL
  standard offpage *
  page302_i57
#ISCELL
  pure_quanta_power gnd *
  page302_i59
#CELL
  pure_quanta q_res *
  page302_i6
#CELL
  pure_quanta q_res *
  page302_i60
#CELL
  pure_quanta mosfet_nch_1d3s *
  page302_i61
#CELL
  pure_quanta q_res *
  page302_i62
#CELL
  pure_quanta q_cap *
  page302_i63
#CELL
  pure_quanta mosfet_nch_1d3s *
  page302_i64
#ISCELL
  standard offpage *
  page302_i65
#ISCELL
  standard offpage *
  page302_i66
#ISCELL
  standard offpage *
  page302_i67
#ISCELL
  standard offpage *
  page302_i68
#ISCELL
  standard offpage *
  page302_i69
#CELL
  pure_quanta q_res *
  page302_i7
#CELL
  pure_quanta q_cap *
  page302_i70
#CELL
  pure_quanta q_res *
  page302_i71
#CELL
  pure_quanta ss15p3sm386a *
  page302_i72
#ISCELL
  pure_quanta_power universal_power *
  page302_i73
#CELL
  pure_quanta q_res *
  page302_i74
#CELL
  pure_quanta mosfet_nch_1d3s *
  page302_i75
#ISCELL
  standard offpage *
  page302_i76
#ISCELL
  pure_quanta_power universal_power *
  page302_i77
#ISCELL
  pure_quanta_power universal_power *
  page302_i78
#CELL
  pure_quanta mosfet_nch_1d3s *
  page302_i79
#CELL
  pure_quanta q_res *
  page302_i8
#CELL
  pure_quanta mosfet_nch_1d3s *
  page302_i80
#CELL
  pure_quanta q_sp_res4p *
  page302_i81
#CELL
  pure_quanta q_res *
  page302_i82
#CELL
  pure_quanta q_res *
  page302_i83
#CELL
  pure_quanta q_res *
  page302_i84
#CELL
  pure_quanta q_res *
  page302_i85
#CELL
  pure_quanta q_res *
  page302_i86
#CELL
  pure_quanta q_res *
  page302_i87
#CELL
  pure_quanta q_res *
  page302_i88
#CELL
  pure_quanta q_res *
  page302_i89
#CELL
  pure_quanta q_res *
  page302_i90
#CELL
  pure_quanta q_res *
  page302_i91
